# S9S_MB_2U (Grand Teton) — schematic netlist excerpt (pin names and nets, part order shuffled) for the footprints in the layout excerpt that follows; sources: Cadence DE-HDL packaged netlist, KiCad conversion of 03242023_DA0F0TMBIJ0_F0T_Motherboard_J_brd_V01_OCP.brd

C2348  Q_CAP  0.1UF 25V 10% X7R  pkg 0402  page 248 : A = P3V3_AUX ; B = GND

U246  NC7SB3157  NC7SB3157P6X EMPTY  pkg SMLF  page 165
  B1  = OCP_V3_2_NOT_PRSNT_RBT_ARB_IN
  GND  = GND
  B0  = OCP_V3_2_RBT_ARB_OUT
  A  = OCP_SFF_RBT_ARB_IN_MUX1
  VCC  = P3V3_AUX
  S  = OCP_V3_2_PRSNT_ALL_R1_N

(kicad_pcb
	(version 20260206)
	(generator "pcbnew")
	(generator_version "10.0")
	(general
		(thickness 1.6)
		(legacy_teardrops no)
	)
	(paper "A4")
	(title_block
		(title "03242023_DA0F0TMBIJ0_F0T_Motherboard_J_brd_V01_OCP.brd")
		(comment 1 "Grand Teton / footprints 1363-1364 of 6105")
	)
	(layers
		(0 "F.Cu" signal "TOP")
		(4 "In1.Cu" signal "GND")
		(6 "In2.Cu" signal "IN1")
		(8 "In3.Cu" signal "GND1")
		(10 "In4.Cu" signal "IN2")
		(12 "In5.Cu" signal "GND2")
		(14 "In6.Cu" signal "IN3")
		(16 "In7.Cu" signal "GND3")
		(18 "In8.Cu" signal "VCC")
		(20 "In9.Cu" signal "VCC1")
		(22 "In10.Cu" signal "GND4")
		(24 "In11.Cu" signal "IN4")
		(26 "In12.Cu" signal "GND5")
		(28 "In13.Cu" signal "IN5")
		(30 "In14.Cu" signal "GND6")
		(32 "In15.Cu" signal "IN6")
		(34 "In16.Cu" signal "GND7")
		(2 "B.Cu" signal "BOTTOM")
		(9 "F.Adhes" user "F.Adhesive")
		(11 "B.Adhes" user "B.Adhesive")
		(13 "F.Paste" user "Package Geometry/Pastemask Top")
		(15 "B.Paste" user "Package Geometry/Pastemask Bottom")
		(5 "F.SilkS" user "Ref Des/Silkscreen Top")
		(7 "B.SilkS" user "Ref Des/Silkscreen Bottom")
		(1 "F.Mask" user "Board Geometry/Soldermask Top")
		(3 "B.Mask" user "Board Geometry/Soldermask Bottom")
		(17 "Dwgs.User" user "User.Drawings")
		(19 "Cmts.User" user "User.Comments")
		(21 "Eco1.User" user "User.Eco1")
		(23 "Eco2.User" user "User.Eco2")
		(25 "Edge.Cuts" user "Board Geometry/Outline")
		(27 "Margin" user)
		(31 "F.CrtYd" user "Package Geometry/Place Bound Top")
		(29 "B.CrtYd" user "Package Geometry/Place Bound Bottom")
		(35 "F.Fab" user "Ref Des/Assembly Top")
		(33 "B.Fab" user "Ref Des/Assembly Bottom")
	)
	(footprint ""
		(layer "F.Cu")
		(at 127.635 -58.003948)
		(property "Reference" "C2348"
			(at 0 0 0)
			(layer "F.SilkS")
			(hide yes)
			(effects
				(font
					(size 1.27 1.27)
				)
			)
		)
		(property "Value" ""
			(at 0 0 0)
			(layer "F.Fab")
			(effects
				(font
					(size 1.27 1.27)
				)
			)
		)
		(duplicate_pad_numbers_are_jumpers no)
		(fp_line
			(start -0.7874 -0.4064)
			(end 0.7874 -0.4064)
			(stroke
				(width 0.1524)
				(type default)
			)
			(layer "F.SilkS")
		)
		(fp_line
			(start -0.7874 0.4064)
			(end -0.7874 -0.4064)
			(stroke
				(width 0.1524)
				(type default)
			)
			(layer "F.SilkS")
		)
		(fp_line
			(start 0.7874 -0.4064)
			(end 0.7874 0.4064)
			(stroke
				(width 0.1524)
				(type default)
			)
			(layer "F.SilkS")
		)
		(fp_line
			(start 0.7874 0.4064)
			(end -0.7874 0.4064)
			(stroke
				(width 0.1524)
				(type default)
			)
			(layer "F.SilkS")
		)
		(fp_line
			(start -0.67945 -0.305054)
			(end -0.12065 -0.305054)
			(stroke
				(width 0.1)
				(type default)
			)
			(layer "F.Fab")
		)
		(fp_line
			(start -0.67945 0.3048)
			(end -0.67945 -0.305054)
			(stroke
				(width 0.1)
				(type default)
			)
			(layer "F.Fab")
		)
		(fp_line
			(start -0.12065 -0.305054)
			(end -0.12065 -0.2794)
			(stroke
				(width 0.1)
				(type default)
			)
			(layer "F.Fab")
		)
		(fp_line
			(start -0.12065 -0.2794)
			(end 0.12065 -0.2794)
			(stroke
				(width 0.1)
				(type default)
			)
			(layer "F.Fab")
		)
		(fp_line
			(start -0.12065 0.2794)
			(end -0.12065 0.3048)
			(stroke
				(width 0.1)
				(type default)
			)
			(layer "F.Fab")
		)
		(fp_line
			(start -0.12065 0.3048)
			(end -0.67945 0.3048)
			(stroke
				(width 0.1)
				(type default)
			)
			(layer "F.Fab")
		)
		(fp_line
			(start 0.120396 0.2794)
			(end -0.12065 0.2794)
			(stroke
				(width 0.1)
				(type default)
			)
			(layer "F.Fab")
		)
		(fp_line
			(start 0.120396 0.3048)
			(end 0.120396 0.2794)
			(stroke
				(width 0.1)
				(type default)
			)
			(layer "F.Fab")
		)
		(fp_line
			(start 0.12065 -0.3048)
			(end 0.67945 -0.3048)
			(stroke
				(width 0.1)
				(type default)
			)
			(layer "F.Fab")
		)
		(fp_line
			(start 0.12065 -0.2794)
			(end 0.12065 -0.3048)
			(stroke
				(width 0.1)
				(type default)
			)
			(layer "F.Fab")
		)
		(fp_line
			(start 0.67945 -0.3048)
			(end 0.67945 0.3048)
			(stroke
				(width 0.1)
				(type default)
			)
			(layer "F.Fab")
		)
		(fp_line
			(start 0.67945 0.3048)
			(end 0.120396 0.3048)
			(stroke
				(width 0.1)
				(type default)
			)
			(layer "F.Fab")
		)
		(pad "1" smd circle
			(at -0.40005 0)
			(size 0 0)
			(layers "F.Cu" "F.Mask" "F.Paste")
			(net "P3V3_AUX")
		)
		(pad "2" smd circle
			(at 0.40005 0)
			(size 0 0)
			(layers "F.Cu" "F.Mask" "F.Paste")
			(net "GND")
		)
	)
	(footprint ""
		(layer "F.Cu")
		(at 136.00684 -38.049708)
		(property "Reference" "U246"
			(at -2.84988 1.82499 0)
			(unlocked yes)
			(layer "F.SilkS")
			(effects
				(font
					(size 0.7874 0.5842)
					(thickness 0.1524)
				)
			)
		)
		(property "Value" ""
			(at 0 0 0)
			(layer "F.Fab")
			(effects
				(font
					(size 1.27 1.27)
				)
			)
		)
		(duplicate_pad_numbers_are_jumpers no)
		(fp_line
			(start -1.7272 1.1176)
			(end -1.7272 -1.1176)
			(stroke
				(width 0.1524)
				(type default)
			)
			(layer "F.SilkS")
		)
		(fp_line
			(start -0.254 -1.1176)
			(end -1.7272 -1.1176)
			(stroke
				(width 0.1524)
				(type default)
			)
			(layer "F.SilkS")
		)
		(fp_line
			(start 0 -0.7366)
			(end -0.254 -1.1176)
			(stroke
				(width 0.1524)
				(type default)
			)
			(layer "F.SilkS")
		)
		(fp_line
			(start 0.254 -1.1176)
			(end 0 -0.7366)
			(stroke
				(width 0.1524)
				(type default)
			)
			(layer "F.SilkS")
		)
		(fp_line
			(start 1.7272 -1.1176)
			(end 0.254 -1.1176)
			(stroke
				(width 0.1524)
				(type default)
			)
			(layer "F.SilkS")
		)
		(fp_line
			(start 1.7272 -1.1176)
			(end 1.7272 1.1176)
			(stroke
				(width 0.1524)
				(type default)
			)
			(layer "F.SilkS")
		)
		(fp_line
			(start 1.7272 1.1176)
			(end -1.7272 1.1176)
			(stroke
				(width 0.1524)
				(type default)
			)
			(layer "F.SilkS")
		)
		(fp_poly
			(pts
				(xy -2.7178 -0.268986) (xy -2.7178 -1.030986) (xy -1.9558 -0.649986)
			)
			(stroke
				(width 0)
				(type default)
			)
			(fill yes)
			(layer "F.SilkS")
		)
		(fp_line
			(start -1.5748 -1.1176)
			(end -1.5748 1.1176)
			(stroke
				(width 0.1)
				(type default)
			)
			(layer "F.Fab")
		)
		(fp_line
			(start -1.5748 1.1176)
			(end 1.5748 1.1176)
			(stroke
				(width 0.1)
				(type default)
			)
			(layer "F.Fab")
		)
		(fp_line
			(start 1.5748 -1.1176)
			(end -1.5748 -1.1176)
			(stroke
				(width 0.1)
				(type default)
			)
			(layer "F.Fab")
		)
		(fp_line
			(start 1.5748 1.1176)
			(end 1.5748 -1.1176)
			(stroke
				(width 0.1)
				(type default)
			)
			(layer "F.Fab")
		)
		(fp_poly
			(pts
				(xy -1.9558 -0.649986) (xy -2.7178 -0.268986) (xy -2.7178 -1.030986)
			)
			(stroke
				(width 0)
				(type default)
			)
			(fill yes)
			(layer "F.Fab")
		)
		(pad "1" smd rect
			(at -0.999998 -0.649986 270)
			(size 0.3556 1.1176)
			(layers "F.Cu" "F.Mask" "F.Paste")
			(net "OCP_V3_2_NOT_PRSNT_RBT_ARB_IN")
		)
		(pad "2" smd rect
			(at -0.999998 0 270)
			(size 0.3556 1.1176)
			(layers "F.Cu" "F.Mask" "F.Paste")
			(net "GND")
		)
		(pad "3" smd rect
			(at -0.999998 0.649986 270)
			(size 0.3556 1.1176)
			(layers "F.Cu" "F.Mask" "F.Paste")
			(net "OCP_V3_2_RBT_ARB_OUT")
		)
		(pad "4" smd rect
			(at 0.999998 0.649986 270)
			(size 0.3556 1.1176)
			(layers "F.Cu" "F.Mask" "F.Paste")
			(net "OCP_SFF_RBT_ARB_IN_MUX1")
		)
		(pad "5" smd rect
			(at 0.999998 0 270)
			(size 0.3556 1.1176)
			(layers "F.Cu" "F.Mask" "F.Paste")
			(net "P3V3_AUX")
		)
		(pad "6" smd rect
			(at 0.999998 -0.649986 270)
			(size 0.3556 1.1176)
			(layers "F.Cu" "F.Mask" "F.Paste")
			(net "OCP_V3_2_PRSNT_ALL_R1_N")
		)
	)
)
